(kicad_pcb
	(version 20260206)
	(generator "pcbnew")
	(generator_version "10.0")
	(general
		(thickness 1.6)
		(legacy_teardrops no)
	)
	(paper "A4")
	(title_block
		(title "03242023_DA0F0TMBIJ0_F0T_Motherboard_J_brd_V01_OCP.brd")
		(comment 1 "Grand Teton / footprints 550-555 of 6105")
	)
	(layers
		(0 "F.Cu" signal "TOP")
		(4 "In1.Cu" signal "GND")
		(6 "In2.Cu" signal "IN1")
		(8 "In3.Cu" signal "GND1")
		(10 "In4.Cu" signal "IN2")
		(12 "In5.Cu" signal "GND2")
		(14 "In6.Cu" signal "IN3")
		(16 "In7.Cu" signal "GND3")
		(18 "In8.Cu" signal "VCC")
		(20 "In9.Cu" signal "VCC1")
		(22 "In10.Cu" signal "GND4")
		(24 "In11.Cu" signal "IN4")
		(26 "In12.Cu" signal "GND5")
		(28 "In13.Cu" signal "IN5")
		(30 "In14.Cu" signal "GND6")
		(32 "In15.Cu" signal "IN6")
		(34 "In16.Cu" signal "GND7")
		(2 "B.Cu" signal "BOTTOM")
		(9 "F.Adhes" user "F.Adhesive")
		(11 "B.Adhes" user "B.Adhesive")
		(13 "F.Paste" user "Package Geometry/Pastemask Top")
		(15 "B.Paste" user "Package Geometry/Pastemask Bottom")
		(5 "F.SilkS" user "Ref Des/Silkscreen Top")
		(7 "B.SilkS" user "Ref Des/Silkscreen Bottom")
		(1 "F.Mask" user "Board Geometry/Soldermask Top")
		(3 "B.Mask" user "Board Geometry/Soldermask Bottom")
		(17 "Dwgs.User" user "User.Drawings")
		(19 "Cmts.User" user "User.Comments")
		(21 "Eco1.User" user "User.Eco1")
		(23 "Eco2.User" user "User.Eco2")
		(25 "Edge.Cuts" user "Board Geometry/Outline")
		(27 "Margin" user)
		(31 "F.CrtYd" user "Package Geometry/Place Bound Top")
		(29 "B.CrtYd" user "Package Geometry/Place Bound Bottom")
		(35 "F.Fab" user "Ref Des/Assembly Top")
		(33 "B.Fab" user "Ref Des/Assembly Bottom")
	)
	(footprint ""
		(layer "F.Cu")
		(at 102.86619 -65.12306 -90)
		(property "Reference" "R3097"
			(at 0 0 270)
			(layer "F.SilkS")
			(hide yes)
			(effects
				(font
					(size 1.27 1.27)
				)
			)
		)
		(property "Value" ""
			(at 0 0 270)
			(layer "F.Fab")
			(effects
				(font
					(size 1.27 1.27)
				)
			)
		)
		(duplicate_pad_numbers_are_jumpers no)
		(fp_line
			(start -0.7874 0.4064)
			(end -0.7874 -0.4064)
			(stroke
				(width 0.1524)
				(type default)
			)
			(layer "F.SilkS")
		)
		(fp_line
			(start 0.7874 0.4064)
			(end -0.7874 0.4064)
			(stroke
				(width 0.1524)
				(type default)
			)
			(layer "F.SilkS")
		)
		(fp_line
			(start -0.7874 -0.4064)
			(end 0.7874 -0.4064)
			(stroke
				(width 0.1524)
				(type default)
			)
			(layer "F.SilkS")
		)
		(fp_line
			(start 0.7874 -0.4064)
			(end 0.7874 0.4064)
			(stroke
				(width 0.1524)
				(type default)
			)
			(layer "F.SilkS")
		)
		(fp_line
			(start -0.67945 0.3048)
			(end -0.67945 -0.305054)
			(stroke
				(width 0.1)
				(type default)
			)
			(layer "F.Fab")
		)
		(fp_line
			(start -0.12065 0.3048)
			(end -0.67945 0.3048)
			(stroke
				(width 0.1)
				(type default)
			)
			(layer "F.Fab")
		)
		(fp_line
			(start 0.120396 0.3048)
			(end 0.120396 0.2794)
			(stroke
				(width 0.1)
				(type default)
			)
			(layer "F.Fab")
		)
		(fp_line
			(start 0.67945 0.3048)
			(end 0.120396 0.3048)
			(stroke
				(width 0.1)
				(type default)
			)
			(layer "F.Fab")
		)
		(fp_line
			(start -0.12065 0.2794)
			(end -0.12065 0.3048)
			(stroke
				(width 0.1)
				(type default)
			)
			(layer "F.Fab")
		)
		(fp_line
			(start 0.120396 0.2794)
			(end -0.12065 0.2794)
			(stroke
				(width 0.1)
				(type default)
			)
			(layer "F.Fab")
		)
		(fp_line
			(start -0.12065 -0.2794)
			(end 0.12065 -0.2794)
			(stroke
				(width 0.1)
				(type default)
			)
			(layer "F.Fab")
		)
		(fp_line
			(start 0.12065 -0.2794)
			(end 0.12065 -0.3048)
			(stroke
				(width 0.1)
				(type default)
			)
			(layer "F.Fab")
		)
		(fp_line
			(start 0.12065 -0.3048)
			(end 0.67945 -0.3048)
			(stroke
				(width 0.1)
				(type default)
			)
			(layer "F.Fab")
		)
		(fp_line
			(start 0.67945 -0.3048)
			(end 0.67945 0.3048)
			(stroke
				(width 0.1)
				(type default)
			)
			(layer "F.Fab")
		)
		(fp_line
			(start -0.67945 -0.305054)
			(end -0.12065 -0.305054)
			(stroke
				(width 0.1)
				(type default)
			)
			(layer "F.Fab")
		)
		(fp_line
			(start -0.12065 -0.305054)
			(end -0.12065 -0.2794)
			(stroke
				(width 0.1)
				(type default)
			)
			(layer "F.Fab")
		)
		(pad "1" smd circle
			(at -0.40005 0 270)
			(size 0 0)
			(layers "F.Cu" "F.Mask" "F.Paste")
			(net "LED_PWRGD_PVNN_MAIN_CPU1")
		)
		(pad "2" smd circle
			(at 0.40005 0 270)
			(size 0 0)
			(layers "F.Cu" "F.Mask" "F.Paste")
			(net "P3V3_AUX")
		)
	)
	(footprint ""
		(layer "F.Cu")
		(at 309.259224 -438.187846 -90)
		(property "Reference" "R4127"
			(at 0 0 270)
			(layer "F.SilkS")
			(hide yes)
			(effects
				(font
					(size 1.27 1.27)
				)
			)
		)
		(property "Value" ""
			(at 0 0 270)
			(layer "F.Fab")
			(effects
				(font
					(size 1.27 1.27)
				)
			)
		)
		(duplicate_pad_numbers_are_jumpers no)
		(fp_line
			(start -0.7874 0.4064)
			(end -0.7874 -0.4064)
			(stroke
				(width 0.1524)
				(type default)
			)
			(layer "F.SilkS")
		)
		(fp_line
			(start 0.7874 0.4064)
			(end -0.7874 0.4064)
			(stroke
				(width 0.1524)
				(type default)
			)
			(layer "F.SilkS")
		)
		(fp_line
			(start -0.7874 -0.4064)
			(end 0.7874 -0.4064)
			(stroke
				(width 0.1524)
				(type default)
			)
			(layer "F.SilkS")
		)
		(fp_line
			(start 0.7874 -0.4064)
			(end 0.7874 0.4064)
			(stroke
				(width 0.1524)
				(type default)
			)
			(layer "F.SilkS")
		)
		(fp_line
			(start -0.67945 0.3048)
			(end -0.67945 -0.305054)
			(stroke
				(width 0.1)
				(type default)
			)
			(layer "F.Fab")
		)
		(fp_line
			(start -0.12065 0.3048)
			(end -0.67945 0.3048)
			(stroke
				(width 0.1)
				(type default)
			)
			(layer "F.Fab")
		)
		(fp_line
			(start 0.120396 0.3048)
			(end 0.120396 0.2794)
			(stroke
				(width 0.1)
				(type default)
			)
			(layer "F.Fab")
		)
		(fp_line
			(start 0.67945 0.3048)
			(end 0.120396 0.3048)
			(stroke
				(width 0.1)
				(type default)
			)
			(layer "F.Fab")
		)
		(fp_line
			(start -0.12065 0.2794)
			(end -0.12065 0.3048)
			(stroke
				(width 0.1)
				(type default)
			)
			(layer "F.Fab")
		)
		(fp_line
			(start 0.120396 0.2794)
			(end -0.12065 0.2794)
			(stroke
				(width 0.1)
				(type default)
			)
			(layer "F.Fab")
		)
		(fp_line
			(start -0.12065 -0.2794)
			(end 0.12065 -0.2794)
			(stroke
				(width 0.1)
				(type default)
			)
			(layer "F.Fab")
		)
		(fp_line
			(start 0.12065 -0.2794)
			(end 0.12065 -0.3048)
			(stroke
				(width 0.1)
				(type default)
			)
			(layer "F.Fab")
		)
		(fp_line
			(start 0.12065 -0.3048)
			(end 0.67945 -0.3048)
			(stroke
				(width 0.1)
				(type default)
			)
			(layer "F.Fab")
		)
		(fp_line
			(start 0.67945 -0.3048)
			(end 0.67945 0.3048)
			(stroke
				(width 0.1)
				(type default)
			)
			(layer "F.Fab")
		)
		(fp_line
			(start -0.67945 -0.305054)
			(end -0.12065 -0.305054)
			(stroke
				(width 0.1)
				(type default)
			)
			(layer "F.Fab")
		)
		(fp_line
			(start -0.12065 -0.305054)
			(end -0.12065 -0.2794)
			(stroke
				(width 0.1)
				(type default)
			)
			(layer "F.Fab")
		)
		(pad "1" smd circle
			(at -0.40005 0 270)
			(size 0 0)
			(layers "F.Cu" "F.Mask" "F.Paste")
			(net "P3V3_AUX")
		)
		(pad "2" smd circle
			(at 0.40005 0 270)
			(size 0 0)
			(layers "F.Cu" "F.Mask" "F.Paste")
			(net "GPU_3V3IO_RSVD1_FFU_N")
		)
	)
	(footprint ""
		(layer "F.Cu")
		(at 35.840162 -122.380502 90)
		(property "Reference" "R1661"
			(at 0 0 90)
			(layer "F.SilkS")
			(hide yes)
			(effects
				(font
					(size 1.27 1.27)
				)
			)
		)
		(property "Value" ""
			(at 0 0 90)
			(layer "F.Fab")
			(effects
				(font
					(size 1.27 1.27)
				)
			)
		)
		(duplicate_pad_numbers_are_jumpers no)
		(fp_line
			(start 0.7874 -0.4064)
			(end 0.7874 0.4064)
			(stroke
				(width 0.1524)
				(type default)
			)
			(layer "F.SilkS")
		)
		(fp_line
			(start -0.7874 -0.4064)
			(end 0.7874 -0.4064)
			(stroke
				(width 0.1524)
				(type default)
			)
			(layer "F.SilkS")
		)
		(fp_line
			(start 0.7874 0.4064)
			(end -0.7874 0.4064)
			(stroke
				(width 0.1524)
				(type default)
			)
			(layer "F.SilkS")
		)
		(fp_line
			(start -0.7874 0.4064)
			(end -0.7874 -0.4064)
			(stroke
				(width 0.1524)
				(type default)
			)
			(layer "F.SilkS")
		)
		(fp_line
			(start -0.12065 -0.305054)
			(end -0.12065 -0.2794)
			(stroke
				(width 0.1)
				(type default)
			)
			(layer "F.Fab")
		)
		(fp_line
			(start -0.67945 -0.305054)
			(end -0.12065 -0.305054)
			(stroke
				(width 0.1)
				(type default)
			)
			(layer "F.Fab")
		)
		(fp_line
			(start 0.67945 -0.3048)
			(end 0.67945 0.3048)
			(stroke
				(width 0.1)
				(type default)
			)
			(layer "F.Fab")
		)
		(fp_line
			(start 0.12065 -0.3048)
			(end 0.67945 -0.3048)
			(stroke
				(width 0.1)
				(type default)
			)
			(layer "F.Fab")
		)
		(fp_line
			(start 0.12065 -0.2794)
			(end 0.12065 -0.3048)
			(stroke
				(width 0.1)
				(type default)
			)
			(layer "F.Fab")
		)
		(fp_line
			(start -0.12065 -0.2794)
			(end 0.12065 -0.2794)
			(stroke
				(width 0.1)
				(type default)
			)
			(layer "F.Fab")
		)
		(fp_line
			(start 0.120396 0.2794)
			(end -0.12065 0.2794)
			(stroke
				(width 0.1)
				(type default)
			)
			(layer "F.Fab")
		)
		(fp_line
			(start -0.12065 0.2794)
			(end -0.12065 0.3048)
			(stroke
				(width 0.1)
				(type default)
			)
			(layer "F.Fab")
		)
		(fp_line
			(start 0.67945 0.3048)
			(end 0.120396 0.3048)
			(stroke
				(width 0.1)
				(type default)
			)
			(layer "F.Fab")
		)
		(fp_line
			(start 0.120396 0.3048)
			(end 0.120396 0.2794)
			(stroke
				(width 0.1)
				(type default)
			)
			(layer "F.Fab")
		)
		(fp_line
			(start -0.12065 0.3048)
			(end -0.67945 0.3048)
			(stroke
				(width 0.1)
				(type default)
			)
			(layer "F.Fab")
		)
		(fp_line
			(start -0.67945 0.3048)
			(end -0.67945 -0.305054)
			(stroke
				(width 0.1)
				(type default)
			)
			(layer "F.Fab")
		)
		(pad "1" smd circle
			(at -0.40005 0 90)
			(size 0 0)
			(layers "F.Cu" "F.Mask" "F.Paste")
			(net "SMB_VR_3V3AUX_SCL")
		)
		(pad "2" smd circle
			(at 0.40005 0 90)
			(size 0 0)
			(layers "F.Cu" "F.Mask" "F.Paste")
			(net "SMB_VR_3V3AUX_SCL_R")
		)
	)
	(footprint ""
		(layer "F.Cu")
		(at 77.381354 -65.082674 -90)
		(property "Reference" "R3080"
			(at 0 0 270)
			(layer "F.SilkS")
			(hide yes)
			(effects
				(font
					(size 1.27 1.27)
				)
			)
		)
		(property "Value" ""
			(at 0 0 270)
			(layer "F.Fab")
			(effects
				(font
					(size 1.27 1.27)
				)
			)
		)
		(duplicate_pad_numbers_are_jumpers no)
		(fp_line
			(start -0.7874 0.4064)
			(end -0.7874 -0.4064)
			(stroke
				(width 0.1524)
				(type default)
			)
			(layer "F.SilkS")
		)
		(fp_line
			(start 0.7874 0.4064)
			(end -0.7874 0.4064)
			(stroke
				(width 0.1524)
				(type default)
			)
			(layer "F.SilkS")
		)
		(fp_line
			(start -0.7874 -0.4064)
			(end 0.7874 -0.4064)
			(stroke
				(width 0.1524)
				(type default)
			)
			(layer "F.SilkS")
		)
		(fp_line
			(start 0.7874 -0.4064)
			(end 0.7874 0.4064)
			(stroke
				(width 0.1524)
				(type default)
			)
			(layer "F.SilkS")
		)
		(fp_line
			(start -0.67945 0.3048)
			(end -0.67945 -0.305054)
			(stroke
				(width 0.1)
				(type default)
			)
			(layer "F.Fab")
		)
		(fp_line
			(start -0.12065 0.3048)
			(end -0.67945 0.3048)
			(stroke
				(width 0.1)
				(type default)
			)
			(layer "F.Fab")
		)
		(fp_line
			(start 0.120396 0.3048)
			(end 0.120396 0.2794)
			(stroke
				(width 0.1)
				(type default)
			)
			(layer "F.Fab")
		)
		(fp_line
			(start 0.67945 0.3048)
			(end 0.120396 0.3048)
			(stroke
				(width 0.1)
				(type default)
			)
			(layer "F.Fab")
		)
		(fp_line
			(start -0.12065 0.2794)
			(end -0.12065 0.3048)
			(stroke
				(width 0.1)
				(type default)
			)
			(layer "F.Fab")
		)
		(fp_line
			(start 0.120396 0.2794)
			(end -0.12065 0.2794)
			(stroke
				(width 0.1)
				(type default)
			)
			(layer "F.Fab")
		)
		(fp_line
			(start -0.12065 -0.2794)
			(end 0.12065 -0.2794)
			(stroke
				(width 0.1)
				(type default)
			)
			(layer "F.Fab")
		)
		(fp_line
			(start 0.12065 -0.2794)
			(end 0.12065 -0.3048)
			(stroke
				(width 0.1)
				(type default)
			)
			(layer "F.Fab")
		)
		(fp_line
			(start 0.12065 -0.3048)
			(end 0.67945 -0.3048)
			(stroke
				(width 0.1)
				(type default)
			)
			(layer "F.Fab")
		)
		(fp_line
			(start 0.67945 -0.3048)
			(end 0.67945 0.3048)
			(stroke
				(width 0.1)
				(type default)
			)
			(layer "F.Fab")
		)
		(fp_line
			(start -0.67945 -0.305054)
			(end -0.12065 -0.305054)
			(stroke
				(width 0.1)
				(type default)
			)
			(layer "F.Fab")
		)
		(fp_line
			(start -0.12065 -0.305054)
			(end -0.12065 -0.2794)
			(stroke
				(width 0.1)
				(type default)
			)
			(layer "F.Fab")
		)
		(pad "1" smd circle
			(at -0.40005 0 270)
			(size 0 0)
			(layers "F.Cu" "F.Mask" "F.Paste")
			(net "LED_RST_PLD_CPU0_DRAM_CD_N")
		)
		(pad "2" smd circle
			(at 0.40005 0 270)
			(size 0 0)
			(layers "F.Cu" "F.Mask" "F.Paste")
			(net "P3V3_AUX")
		)
	)
	(footprint ""
		(layer "F.Cu")
		(at 159.258 -126.365 -90)
		(property "Reference" "R4640"
			(at 0 0 270)
			(layer "F.SilkS")
			(hide yes)
			(effects
				(font
					(size 1.27 1.27)
				)
			)
		)
		(property "Value" ""
			(at 0 0 270)
			(layer "F.Fab")
			(effects
				(font
					(size 1.27 1.27)
				)
			)
		)
		(duplicate_pad_numbers_are_jumpers no)
		(fp_line
			(start -2.234946 0.9271)
			(end -2.234946 -0.9271)
			(stroke
				(width 0.1524)
				(type default)
			)
			(layer "F.SilkS")
		)
		(fp_line
			(start 2.234946 0.9271)
			(end -2.234946 0.9271)
			(stroke
				(width 0.1524)
				(type default)
			)
			(layer "F.SilkS")
		)
		(fp_line
			(start -2.234946 -0.9271)
			(end 2.234946 -0.9271)
			(stroke
				(width 0.1524)
				(type default)
			)
			(layer "F.SilkS")
		)
		(fp_line
			(start 2.234946 -0.9271)
			(end 2.234946 0.9271)
			(stroke
				(width 0.1524)
				(type default)
			)
			(layer "F.SilkS")
		)
		(fp_line
			(start -1.575054 0.824992)
			(end 1.575054 0.824992)
			(stroke
				(width 0.1)
				(type default)
			)
			(layer "F.Fab")
		)
		(fp_line
			(start 1.575054 0.824992)
			(end 1.575054 -0.824992)
			(stroke
				(width 0.1)
				(type default)
			)
			(layer "F.Fab")
		)
		(fp_line
			(start -1.575054 -0.824992)
			(end -1.575054 0.824992)
			(stroke
				(width 0.1)
				(type default)
			)
			(layer "F.Fab")
		)
		(fp_line
			(start 1.575054 -0.824992)
			(end -1.575054 -0.824992)
			(stroke
				(width 0.1)
				(type default)
			)
			(layer "F.Fab")
		)
		(pad "1" smd rect
			(at -1.599946 0 270)
			(size 1.016 1.6002)
			(layers "F.Cu" "F.Mask" "F.Paste")
			(net "P5V")
		)
		(pad "2" smd rect
			(at 1.599946 0 270)
			(size 1.016 1.6002)
			(layers "F.Cu" "F.Mask" "F.Paste")
			(net "VR_P5V_EN_D")
		)
	)
	(footprint ""
		(layer "F.Cu")
		(at 374.16359 -64.866012)
		(property "Reference" "R756"
			(at 0 0 0)
			(layer "F.SilkS")
			(hide yes)
			(effects
				(font
					(size 1.27 1.27)
				)
			)
		)
		(property "Value" ""
			(at 0 0 0)
			(layer "F.Fab")
			(effects
				(font
					(size 1.27 1.27)
				)
			)
		)
		(duplicate_pad_numbers_are_jumpers no)
		(fp_line
			(start -0.7874 -0.4064)
			(end 0.7874 -0.4064)
			(stroke
				(width 0.1524)
				(type default)
			)
			(layer "F.SilkS")
		)
		(fp_line
			(start -0.7874 0.4064)
			(end -0.7874 -0.4064)
			(stroke
				(width 0.1524)
				(type default)
			)
			(layer "F.SilkS")
		)
		(fp_line
			(start 0.7874 -0.4064)
			(end 0.7874 0.4064)
			(stroke
				(width 0.1524)
				(type default)
			)
			(layer "F.SilkS")
		)
		(fp_line
			(start 0.7874 0.4064)
			(end -0.7874 0.4064)
			(stroke
				(width 0.1524)
				(type default)
			)
			(layer "F.SilkS")
		)
		(fp_line
			(start -0.67945 -0.305054)
			(end -0.12065 -0.305054)
			(stroke
				(width 0.1)
				(type default)
			)
			(layer "F.Fab")
		)
		(fp_line
			(start -0.67945 0.3048)
			(end -0.67945 -0.305054)
			(stroke
				(width 0.1)
				(type default)
			)
			(layer "F.Fab")
		)
		(fp_line
			(start -0.12065 -0.305054)
			(end -0.12065 -0.2794)
			(stroke
				(width 0.1)
				(type default)
			)
			(layer "F.Fab")
		)
		(fp_line
			(start -0.12065 -0.2794)
			(end 0.12065 -0.2794)
			(stroke
				(width 0.1)
				(type default)
			)
			(layer "F.Fab")
		)
		(fp_line
			(start -0.12065 0.2794)
			(end -0.12065 0.3048)
			(stroke
				(width 0.1)
				(type default)
			)
			(layer "F.Fab")
		)
		(fp_line
			(start -0.12065 0.3048)
			(end -0.67945 0.3048)
			(stroke
				(width 0.1)
				(type default)
			)
			(layer "F.Fab")
		)
		(fp_line
			(start 0.120396 0.2794)
			(end -0.12065 0.2794)
			(stroke
				(width 0.1)
				(type default)
			)
			(layer "F.Fab")
		)
		(fp_line
			(start 0.120396 0.3048)
			(end 0.120396 0.2794)
			(stroke
				(width 0.1)
				(type default)
			)
			(layer "F.Fab")
		)
		(fp_line
			(start 0.12065 -0.3048)
			(end 0.67945 -0.3048)
			(stroke
				(width 0.1)
				(type default)
			)
			(layer "F.Fab")
		)
		(fp_line
			(start 0.12065 -0.2794)
			(end 0.12065 -0.3048)
			(stroke
				(width 0.1)
				(type default)
			)
			(layer "F.Fab")
		)
		(fp_line
			(start 0.67945 -0.3048)
			(end 0.67945 0.3048)
			(stroke
				(width 0.1)
				(type default)
			)
			(layer "F.Fab")
		)
		(fp_line
			(start 0.67945 0.3048)
			(end 0.120396 0.3048)
			(stroke
				(width 0.1)
				(type default)
			)
			(layer "F.Fab")
		)
		(pad "1" smd circle
			(at -0.40005 0)
			(size 0 0)
			(layers "F.Cu" "F.Mask" "F.Paste")
			(net "JTAG_DBP_PRDY_N")
		)
		(pad "2" smd circle
			(at 0.40005 0)
			(size 0 0)
			(layers "F.Cu" "F.Mask" "F.Paste")
			(net "H_DBP_PRDY_N_PCH")
		)
	)
)
